(kicad_pcb
	(version 20241229)
	(generator "pcbnew")
	(generator_version "9.0")
	(general
		(thickness 1.711)
		(legacy_teardrops no)
	)
	(paper "A4")
	(title_block
		(title "Antmicro Baseboard for Jetson AGX Thor")
		(date "2026-02-18")
		(rev "1.1.0")
		(company "Antmicro Ltd")
		(comment 1 "www.antmicro.com")
		(comment 9 "footprints 279-282 of 1170")
	)
	(layers
		(0 "F.Cu" signal)
		(4 "In1.Cu" signal)
		(6 "In2.Cu" signal)
		(8 "In3.Cu" signal)
		(10 "In4.Cu" jumper)
		(12 "In5.Cu" signal)
		(14 "In6.Cu" signal)
		(16 "In7.Cu" signal)
		(18 "In8.Cu" signal)
		(2 "B.Cu" signal)
		(9 "F.Adhes" user "F.Adhesive")
		(11 "B.Adhes" user "B.Adhesive")
		(13 "F.Paste" user)
		(15 "B.Paste" user)
		(5 "F.SilkS" user "F.Silkscreen")
		(7 "B.SilkS" user "B.Silkscreen")
		(1 "F.Mask" user)
		(3 "B.Mask" user)
		(17 "Dwgs.User" user "User.Drawings")
		(19 "Cmts.User" user "User.Comments")
		(21 "Eco1.User" user "User.Eco1")
		(23 "Eco2.User" user "User.Eco2")
		(25 "Edge.Cuts" user)
		(27 "Margin" user)
		(31 "F.CrtYd" user "F.Courtyard")
		(29 "B.CrtYd" user "B.Courtyard")
		(35 "F.Fab" user)
		(33 "B.Fab" user)
	)
	(footprint "antmicro-footprints:TP_SMD_0.75mm"
		(layer "F.Cu")
		(at 64.91 58.24 90)
		(property "Reference" "TP28"
			(at 1.54 -2.26 90)
			(layer "F.SilkS")
			(effects
				(font
					(size 0.7 0.7)
					(thickness 0.15)
				)
				(justify left bottom)
			)
		)
		(property "Value" "TP_0.75mm_SMD"
			(at 0 1.2 90)
			(layer "F.Fab")
			(effects
				(font
					(size 0.7 0.7)
					(thickness 0.15)
				)
				(justify left bottom)
			)
		)
		(property "Description" "SMT test point"
			(at 0 0 90)
			(layer "F.Fab")
			(hide yes)
			(effects
				(font
					(size 1.27 1.27)
					(thickness 0.15)
				)
			)
		)
		(property "MPN" ""
			(at 0 0 90)
			(unlocked yes)
			(layer "F.Fab")
			(hide yes)
			(effects
				(font
					(size 1 1)
					(thickness 0.15)
				)
			)
		)
		(property "Manufacturer" ""
			(at 0 0 90)
			(unlocked yes)
			(layer "F.Fab")
			(hide yes)
			(effects
				(font
					(size 1 1)
					(thickness 0.15)
				)
			)
		)
		(property "Author" "Antmicro"
			(at 0 0 90)
			(unlocked yes)
			(layer "F.Fab")
			(hide yes)
			(effects
				(font
					(size 1 1)
					(thickness 0.15)
				)
			)
		)
		(property "License" "Apache-2.0"
			(at 0 0 90)
			(unlocked yes)
			(layer "F.Fab")
			(hide yes)
			(effects
				(font
					(size 1 1)
					(thickness 0.15)
				)
			)
		)
		(sheetname "/CSI/")
		(sheetfile "csi.kicad_sch")
		(attr exclude_from_pos_files exclude_from_bom)
		(fp_circle
			(center 0 0)
			(end 0.475 0)
			(stroke
				(width 0.05)
				(type default)
			)
			(fill no)
			(layer "F.CrtYd")
		)
		(fp_text user "Author: Antmicro"
			(at -0.4 3.901 90)
			(layer "F.Fab")
			(effects
				(font
					(size 0.7 0.7)
					(thickness 0.15)
				)
				(justify left bottom)
			)
		)
		(fp_text user "${REFERENCE}"
			(at -0.4 2.7 90)
			(layer "F.Fab")
			(effects
				(font
					(size 0.7 0.7)
					(thickness 0.15)
				)
				(justify left bottom)
			)
		)
		(fp_text user "License: Apache-2.0"
			(at -0.4 5.101 90)
			(layer "F.Fab")
			(effects
				(font
					(size 0.7 0.7)
					(thickness 0.15)
				)
				(justify left bottom)
			)
		)
		(pad "1" smd circle
			(at 0 0 90)
			(size 0.75 0.75)
			(layers "F.Cu" "F.Mask")
			(net 1052 "/CSI/MUX_I2C_7_SCL")
			(pinfunction "1")
			(pintype "passive")
		)
	)
	(footprint "antmicro-footprints:C_0402_1005Metric"
		(layer "F.Cu")
		(at 193.8 82.4)
		(descr "Capacitor SMD 0402")
		(tags "capacitor SMD 0402")
		(property "Reference" "C122"
			(at -1.5 -0.6 0)
			(layer "F.SilkS")
			(effects
				(font
					(size 0.7 0.7)
					(thickness 0.15)
				)
				(justify left bottom)
			)
		)
		(property "Value" "C_100n_0402"
			(at -1.022927 2.155213 0)
			(layer "F.Fab")
			(effects
				(font
					(size 0.7 0.7)
					(thickness 0.15)
				)
				(justify left bottom)
			)
		)
		(property "Datasheet" "https://www.murata.com/products/productdetail?partno=GRM155R61H104KE14%23"
			(at 0 0 0)
			(layer "F.Fab")
			(hide yes)
			(effects
				(font
					(size 1.27 1.27)
					(thickness 0.15)
				)
			)
		)
		(property "Description" "SMD Multilayer Ceramic Capacitor, 0.1 µF, 50 V, 0402 [1005 Metric], ± 10%, X5R, GRM Series"
			(at 0 0 0)
			(layer "F.Fab")
			(hide yes)
			(effects
				(font
					(size 1.27 1.27)
					(thickness 0.15)
				)
			)
		)
		(property "Manufacturer" "Murata"
			(at 0 0 0)
			(unlocked yes)
			(layer "F.Fab")
			(hide yes)
			(effects
				(font
					(size 1 1)
					(thickness 0.15)
				)
			)
		)
		(property "MPN" "GRM155R61H104KE14D"
			(at 0 0 0)
			(unlocked yes)
			(layer "F.Fab")
			(hide yes)
			(effects
				(font
					(size 1 1)
					(thickness 0.15)
				)
			)
		)
		(property "Val" "100n"
			(at 0 0 0)
			(unlocked yes)
			(layer "F.Fab")
			(hide yes)
			(effects
				(font
					(size 1 1)
					(thickness 0.15)
				)
			)
		)
		(property "License" "Apache-2.0"
			(at 0 0 0)
			(unlocked yes)
			(layer "F.Fab")
			(hide yes)
			(effects
				(font
					(size 1 1)
					(thickness 0.15)
				)
			)
		)
		(property "Author" "Antmicro"
			(at 0 0 0)
			(unlocked yes)
			(layer "F.Fab")
			(hide yes)
			(effects
				(font
					(size 1 1)
					(thickness 0.15)
				)
			)
		)
		(property "Voltage" "50V"
			(at 0 0 0)
			(unlocked yes)
			(layer "F.Fab")
			(hide yes)
			(effects
				(font
					(size 1 1)
					(thickness 0.15)
				)
			)
		)
		(property "Dielectric" "X5R"
			(at 0 0 0)
			(unlocked yes)
			(layer "F.Fab")
			(hide yes)
			(effects
				(font
					(size 1 1)
					(thickness 0.15)
				)
			)
		)
		(sheetname "/USB Debug, PD/")
		(sheetfile "usb_debug_pd.kicad_sch")
		(attr smd)
		(fp_poly
			(pts
				(xy -0.925 -0.47) (xy -0.925 0.47) (xy 0.925 0.47) (xy 0.925 -0.47)
			)
			(stroke
				(width 0.05)
				(type default)
			)
			(fill no)
			(layer "F.CrtYd")
		)
		(fp_line
			(start -0.494 -0.25)
			(end 0.504 -0.25)
			(stroke
				(width 0.15)
				(type solid)
			)
			(layer "F.Fab")
		)
		(fp_line
			(start -0.494 0.248)
			(end -0.494 -0.25)
			(stroke
				(width 0.15)
				(type solid)
			)
			(layer "F.Fab")
		)
		(fp_line
			(start 0.504 -0.25)
			(end 0.504 0.248)
			(stroke
				(width 0.15)
				(type solid)
			)
			(layer "F.Fab")
		)
		(fp_line
			(start 0.504 0.248)
			(end -0.494 0.248)
			(stroke
				(width 0.15)
				(type solid)
			)
			(layer "F.Fab")
		)
		(fp_text user "${REFERENCE}"
			(at -0.939 4.599 0)
			(layer "F.Fab")
			(effects
				(font
					(size 0.7 0.7)
					(thickness 0.15)
				)
				(justify left bottom)
			)
		)
		(fp_text user "Author: Antmicro"
			(at -0.939 3.399 0)
			(layer "F.Fab")
			(effects
				(font
					(size 0.7 0.7)
					(thickness 0.15)
				)
				(justify left bottom)
			)
		)
		(fp_text user "License: Apache-2.0"
			(at -0.939 5.799 0)
			(layer "F.Fab")
			(effects
				(font
					(size 0.7 0.7)
					(thickness 0.15)
				)
				(justify left bottom)
			)
		)
		(pad "1" smd roundrect
			(at -0.48 0)
			(size 0.59 0.64)
			(layers "F.Cu" "F.Mask" "F.Paste")
			(roundrect_rratio 0.25)
			(net 1 "GND")
			(pintype "passive")
		)
		(pad "2" smd roundrect
			(at 0.48 0)
			(size 0.59 0.64)
			(layers "F.Cu" "F.Mask" "F.Paste")
			(roundrect_rratio 0.25)
			(net 271 "FLASH_PWR")
			(pintype "passive")
		)
	)
	(footprint "antmicro-footprints:LED_0603_1608Metric_G"
		(layer "F.Cu")
		(at 222.13 74.869951 180)
		(descr "LED SMD 0603 Green")
		(tags "LED SMD 0603 Green")
		(property "Reference" "D21"
			(at 0.69 -2.520049 180)
			(layer "F.SilkS")
			(effects
				(font
					(size 0.7 0.7)
					(thickness 0.15)
				)
				(justify left bottom)
			)
		)
		(property "Value" "LED_G_0603_LTST-C190GKT"
			(at -0.001 1.599 180)
			(layer "F.Fab")
			(effects
				(font
					(size 0.7 0.7)
					(thickness 0.15)
				)
				(justify left bottom)
			)
		)
		(property "Datasheet" "https://media.digikey.com/pdf/Data%20Sheets/Lite-On%20PDFs/LTST-C190GKT.pdf"
			(at 0 0 180)
			(layer "F.Fab")
			(hide yes)
			(effects
				(font
					(size 1.27 1.27)
					(thickness 0.15)
				)
			)
		)
		(property "Description" "LED, Green, SMD, 0603, 20 mA, 2.1 V, 569 nm"
			(at 0 0 180)
			(layer "F.Fab")
			(hide yes)
			(effects
				(font
					(size 1.27 1.27)
					(thickness 0.15)
				)
			)
		)
		(property "MPN" "LTST-C190GKT"
			(at 0 0 180)
			(unlocked yes)
			(layer "F.Fab")
			(hide yes)
			(effects
				(font
					(size 1 1)
					(thickness 0.15)
				)
			)
		)
		(property "Manufacturer" "Lite-On"
			(at 0 0 180)
			(unlocked yes)
			(layer "F.Fab")
			(hide yes)
			(effects
				(font
					(size 1 1)
					(thickness 0.15)
				)
			)
		)
		(property "Author" "Antmicro"
			(at 0 0 180)
			(unlocked yes)
			(layer "F.Fab")
			(hide yes)
			(effects
				(font
					(size 1 1)
					(thickness 0.15)
				)
			)
		)
		(property "License" "Apache-2.0"
			(at 0 0 180)
			(unlocked yes)
			(layer "F.Fab")
			(hide yes)
			(effects
				(font
					(size 1 1)
					(thickness 0.15)
				)
			)
		)
		(property "Color" "Green"
			(at 0 0 180)
			(unlocked yes)
			(layer "F.Fab")
			(hide yes)
			(effects
				(font
					(size 1 1)
					(thickness 0.15)
				)
			)
		)
		(sheetname "/USB Debug, PD/")
		(sheetfile "usb_debug_pd.kicad_sch")
		(attr smd)
		(fp_line
			(start 0.22 0.35)
			(end -0.22 0.35)
			(stroke
				(width 0.15)
				(type solid)
			)
			(layer "F.SilkS")
		)
		(fp_line
			(start 0.22 -0.35)
			(end -0.22 -0.35)
			(stroke
				(width 0.15)
				(type solid)
			)
			(layer "F.SilkS")
		)
		(fp_line
			(start 0.105328 0.201008)
			(end 0.105328 -0.198992)
			(stroke
				(width 0.1)
				(type solid)
			)
			(layer "F.SilkS")
		)
		(fp_line
			(start 0.105328 0.201008)
			(end -0.094672 0.001008)
			(stroke
				(width 0.1)
				(type solid)
			)
			(layer "F.SilkS")
		)
		(fp_line
			(start 0.105328 0.001008)
			(end 0.24 0.001)
			(stroke
				(width 0.1)
				(type solid)
			)
			(layer "F.SilkS")
		)
		(fp_line
			(start -0.094672 0.201008)
			(end -0.094672 -0.198992)
			(stroke
				(width 0.1)
				(type solid)
			)
			(layer "F.SilkS")
		)
		(fp_line
			(start -0.094672 0.001008)
			(end 0.105328 -0.198992)
			(stroke
				(width 0.1)
				(type solid)
			)
			(layer "F.SilkS")
		)
		(fp_line
			(start -0.094672 0.001008)
			(end -0.24 0.001008)
			(stroke
				(width 0.1)
				(type solid)
			)
			(layer "F.SilkS")
		)
		(fp_line
			(start -1.18 -0.319)
			(end -1.18 0.321)
			(stroke
				(width 0.15)
				(type solid)
			)
			(layer "F.SilkS")
		)
		(fp_rect
			(start 1.25 0.65)
			(end -1.25 -0.65)
			(stroke
				(width 0.05)
				(type solid)
			)
			(fill no)
			(layer "F.CrtYd")
		)
		(fp_line
			(start 0.599 0)
			(end 0.201 0)
			(stroke
				(width 0.15)
				(type solid)
			)
			(layer "F.Fab")
		)
		(fp_line
			(start 0.201 0.2)
			(end 0.201 0)
			(stroke
				(width 0.15)
				(type solid)
			)
			(layer "F.Fab")
		)
		(fp_line
			(start 0.201 0)
			(end 0.201 -0.202)
			(stroke
				(width 0.15)
				(type solid)
			)
			(layer "F.Fab")
		)
		(fp_line
			(start 0.201 -0.202)
			(end -0.101 0)
			(stroke
				(width 0.15)
				(type solid)
			)
			(layer "F.Fab")
		)
		(fp_line
			(start -0.101 0)
			(end 0.201 0.2)
			(stroke
				(width 0.15)
				(type solid)
			)
			(layer "F.Fab")
		)
		(fp_line
			(start -0.199 0.2)
			(end -0.199 0.1)
			(stroke
				(width 0.15)
				(type solid)
			)
			(layer "F.Fab")
		)
		(fp_line
			(start -0.199 0)
			(end -0.597 0)
			(stroke
				(width 0.15)
				(type solid)
			)
			(layer "F.Fab")
		)
		(fp_line
			(start -0.199 -0.202)
			(end -0.199 0.1)
			(stroke
				(width 0.15)
				(type solid)
			)
			(layer "F.Fab")
		)
		(fp_rect
			(start 0.848 0.4)
			(end -0.85 -0.402)
			(stroke
				(width 0.15)
				(type solid)
			)
			(fill no)
			(layer "F.Fab")
		)
		(fp_text user "${REFERENCE}"
			(at -1.4224 5.999 180)
			(layer "F.Fab")
			(effects
				(font
					(size 0.7 0.7)
					(thickness 0.15)
				)
				(justify left bottom)
			)
		)
		(fp_text user "Author: Antmicro"
			(at -1.4224 4.799 180)
			(layer "F.Fab")
			(effects
				(font
					(size 0.7 0.7)
					(thickness 0.15)
				)
				(justify left bottom)
			)
		)
		(fp_text user "License: Apache-2.0"
			(at -1.4224 3.599 180)
			(layer "F.Fab")
			(effects
				(font
					(size 0.7 0.7)
					(thickness 0.15)
				)
				(justify left bottom)
			)
		)
		(pad "1" smd roundrect
			(at -0.7 0)
			(size 0.8 1)
			(layers "F.Cu" "F.Mask" "F.Paste")
			(roundrect_rratio 0.2)
			(net 537 "/USB Debug, PD/FTDI_LED_RX")
			(pinfunction "C")
			(pintype "passive")
		)
		(pad "2" smd roundrect
			(at 0.7 0)
			(size 0.8 1)
			(layers "F.Cu" "F.Mask" "F.Paste")
			(roundrect_rratio 0.2)
			(net 538 "Net-(D21-A)")
			(pinfunction "A")
			(pintype "passive")
		)
	)
	(footprint "antmicro-footprints:C_0402_1005Metric"
		(layer "F.Cu")
		(at 208.86 134.8 90)
		(descr "Capacitor SMD 0402")
		(tags "capacitor SMD 0402")
		(property "Reference" "C256"
			(at -1.6 13.92 90)
			(layer "F.SilkS")
			(effects
				(font
					(size 0.7 0.7)
					(thickness 0.15)
				)
				(justify left bottom)
			)
		)
		(property "Value" "C_100n_0402"
			(at -1.022927 2.155213 90)
			(layer "F.Fab")
			(effects
				(font
					(size 0.7 0.7)
					(thickness 0.15)
				)
				(justify left bottom)
			)
		)
		(property "Datasheet" "https://www.murata.com/products/productdetail?partno=GRM155R61H104KE14%23"
			(at 0 0 90)
			(layer "F.Fab")
			(hide yes)
			(effects
				(font
					(size 1.27 1.27)
					(thickness 0.15)
				)
			)
		)
		(property "Description" "SMD Multilayer Ceramic Capacitor, 0.1 µF, 50 V, 0402 [1005 Metric], ± 10%, X5R, GRM Series"
			(at 0 0 90)
			(layer "F.Fab")
			(hide yes)
			(effects
				(font
					(size 1.27 1.27)
					(thickness 0.15)
				)
			)
		)
		(property "Manufacturer" "Murata"
			(at 0 0 90)
			(unlocked yes)
			(layer "F.Fab")
			(hide yes)
			(effects
				(font
					(size 1 1)
					(thickness 0.15)
				)
			)
		)
		(property "MPN" "GRM155R61H104KE14D"
			(at 0 0 90)
			(unlocked yes)
			(layer "F.Fab")
			(hide yes)
			(effects
				(font
					(size 1 1)
					(thickness 0.15)
				)
			)
		)
		(property "Val" "100n"
			(at 0 0 90)
			(unlocked yes)
			(layer "F.Fab")
			(hide yes)
			(effects
				(font
					(size 1 1)
					(thickness 0.15)
				)
			)
		)
		(property "License" "Apache-2.0"
			(at 0 0 90)
			(unlocked yes)
			(layer "F.Fab")
			(hide yes)
			(effects
				(font
					(size 1 1)
					(thickness 0.15)
				)
			)
		)
		(property "Author" "Antmicro"
			(at 0 0 90)
			(unlocked yes)
			(layer "F.Fab")
			(hide yes)
			(effects
				(font
					(size 1 1)
					(thickness 0.15)
				)
			)
		)
		(property "Voltage" "50V"
			(at 0 0 90)
			(unlocked yes)
			(layer "F.Fab")
			(hide yes)
			(effects
				(font
					(size 1 1)
					(thickness 0.15)
				)
			)
		)
		(property "Dielectric" "X5R"
			(at 0 0 90)
			(unlocked yes)
			(layer "F.Fab")
			(hide yes)
			(effects
				(font
					(size 1 1)
					(thickness 0.15)
				)
			)
		)
		(sheetname "/USB Hub/")
		(sheetfile "usb_hub.kicad_sch")
		(attr smd)
		(fp_rect
			(start -0.925 -0.47)
			(end 0.925 0.47)
			(stroke
				(width 0.05)
				(type default)
			)
			(fill no)
			(layer "F.CrtYd")
		)
		(fp_line
			(start 0.504 -0.25)
			(end 0.504 0.248)
			(stroke
				(width 0.15)
				(type solid)
			)
			(layer "F.Fab")
		)
		(fp_line
			(start -0.494 -0.25)
			(end 0.504 -0.25)
			(stroke
				(width 0.15)
				(type solid)
			)
			(layer "F.Fab")
		)
		(fp_line
			(start 0.504 0.248)
			(end -0.494 0.248)
			(stroke
				(width 0.15)
				(type solid)
			)
			(layer "F.Fab")
		)
		(fp_line
			(start -0.494 0.248)
			(end -0.494 -0.25)
			(stroke
				(width 0.15)
				(type solid)
			)
			(layer "F.Fab")
		)
		(fp_text user "${REFERENCE}"
			(at -0.939 4.599 90)
			(layer "F.Fab")
			(effects
				(font
					(size 0.7 0.7)
					(thickness 0.15)
				)
				(justify left bottom)
			)
		)
		(fp_text user "License: Apache-2.0"
			(at -0.939 5.799 90)
			(layer "F.Fab")
			(effects
				(font
					(size 0.7 0.7)
					(thickness 0.15)
				)
				(justify left bottom)
			)
		)
		(fp_text user "Author: Antmicro"
			(at -0.939 3.399 90)
			(layer "F.Fab")
			(effects
				(font
					(size 0.7 0.7)
					(thickness 0.15)
				)
				(justify left bottom)
			)
		)
		(pad "1" smd roundrect
			(at -0.48 0 90)
			(size 0.59 0.64)
			(layers "F.Cu" "F.Mask" "F.Paste")
			(roundrect_rratio 0.25)
			(net 662 "/SoM_IO2/USBSS2.TX-")
			(pintype "passive")
		)
		(pad "2" smd roundrect
			(at 0.48 0 90)
			(size 0.59 0.64)
			(layers "F.Cu" "F.Mask" "F.Paste")
			(roundrect_rratio 0.25)
			(net 1135 "/USB Hub/USBSS_RX_N")
			(pintype "passive")
		)
	)
)
